(kicad_pcb
	(version 20241229)
	(generator "pcbnew")
	(generator_version "9.0")
	(general
		(thickness 1.6)
		(legacy_teardrops no)
	)
	(paper "A4")
	(title_block
		(title "environment-sensor")
		(comment 1 "footprints 80-86 of 109")
	)
	(layers
		(0 "F.Cu" signal)
		(4 "In1.Cu" signal)
		(6 "In2.Cu" signal)
		(2 "B.Cu" signal)
		(9 "F.Adhes" user "F.Adhesive")
		(11 "B.Adhes" user "B.Adhesive")
		(13 "F.Paste" user)
		(15 "B.Paste" user)
		(5 "F.SilkS" user "F.Silkscreen")
		(7 "B.SilkS" user "B.Silkscreen")
		(1 "F.Mask" user)
		(3 "B.Mask" user)
		(17 "Dwgs.User" user "User.Drawings")
		(19 "Cmts.User" user "User.Comments")
		(21 "Eco1.User" user "User.Eco1")
		(23 "Eco2.User" user "User.Eco2")
		(25 "Edge.Cuts" user)
		(27 "Margin" user)
		(31 "F.CrtYd" user "F.Courtyard")
		(29 "B.CrtYd" user "B.Courtyard")
		(35 "F.Fab" user)
		(33 "B.Fab" user)
	)
	(footprint "antmicro-footprints:C_0402_1005Metric"
		(layer "F.Cu")
		(at 169.55 136.15 180)
		(descr "Capacitor SMD 0402")
		(tags "capacitor SMD 0402")
		(property "Reference" "C2"
			(at 0.95 -0.35 0)
			(layer "F.SilkS")
			(effects
				(font
					(size 0.7 0.7)
					(thickness 0.15)
				)
				(justify right bottom)
			)
		)
		(property "Value" "C_100n_0402"
			(at 0 1.4 0)
			(layer "F.Fab")
			(effects
				(font
					(size 0.7 0.7)
					(thickness 0.15)
				)
				(justify right bottom)
			)
		)
		(property "Description" "SMD Multilayer Ceramic Capacitor, 0.1 µF, 50 V, 0402 [1005 Metric], ± 10%, X5R, GRM Series"
			(at 0 0 180)
			(layer "F.Fab")
			(hide yes)
			(effects
				(font
					(size 1.27 1.27)
					(thickness 0.15)
				)
			)
		)
		(property "Author" "Antmicro"
			(at 339.1 272.3 0)
			(layer "F.Fab")
			(hide yes)
			(effects
				(font
					(size 1 1)
					(thickness 0.15)
				)
			)
		)
		(property "Dielectric" "X5R"
			(at 339.1 272.3 0)
			(layer "F.Fab")
			(hide yes)
			(effects
				(font
					(size 1 1)
					(thickness 0.15)
				)
			)
		)
		(property "License" "Apache-2.0"
			(at 339.1 272.3 0)
			(layer "F.Fab")
			(hide yes)
			(effects
				(font
					(size 1 1)
					(thickness 0.15)
				)
			)
		)
		(property "MPN" "GRM155R61H104KE14D"
			(at 339.1 272.3 0)
			(layer "F.Fab")
			(hide yes)
			(effects
				(font
					(size 1 1)
					(thickness 0.15)
				)
			)
		)
		(property "Manufacturer" "Murata"
			(at 339.1 272.3 0)
			(layer "F.Fab")
			(hide yes)
			(effects
				(font
					(size 1 1)
					(thickness 0.15)
				)
			)
		)
		(property "Public" "False"
			(at 339.1 272.3 0)
			(layer "F.Fab")
			(hide yes)
			(effects
				(font
					(size 1 1)
					(thickness 0.15)
				)
			)
		)
		(property "Val" "100n"
			(at 339.1 272.3 0)
			(layer "F.Fab")
			(hide yes)
			(effects
				(font
					(size 1 1)
					(thickness 0.15)
				)
			)
		)
		(property "Voltage" "50V"
			(at 339.1 272.3 0)
			(layer "F.Fab")
			(hide yes)
			(effects
				(font
					(size 1 1)
					(thickness 0.15)
				)
			)
		)
		(sheetfile "environment-sensor.kicad_sch")
		(attr smd)
		(fp_rect
			(start -0.925 -0.47)
			(end 0.925 0.47)
			(stroke
				(width 0.05)
				(type default)
			)
			(fill no)
			(layer "F.CrtYd")
		)
		(fp_line
			(start 0.504 0.248)
			(end -0.494 0.248)
			(stroke
				(width 0.15)
				(type solid)
			)
			(layer "F.Fab")
		)
		(fp_line
			(start 0.504 -0.25)
			(end 0.504 0.248)
			(stroke
				(width 0.15)
				(type solid)
			)
			(layer "F.Fab")
		)
		(fp_line
			(start -0.494 0.248)
			(end -0.494 -0.25)
			(stroke
				(width 0.15)
				(type solid)
			)
			(layer "F.Fab")
		)
		(fp_line
			(start -0.494 -0.25)
			(end 0.504 -0.25)
			(stroke
				(width 0.15)
				(type solid)
			)
			(layer "F.Fab")
		)
		(pad "1" smd roundrect
			(at -0.48 0 180)
			(size 0.59 0.64)
			(layers "F.Cu" "F.Mask" "F.Paste")
			(roundrect_rratio 0.25)
			(net 1 "GND")
			(pintype "passive")
		)
		(pad "2" smd roundrect
			(at 0.48 0 180)
			(size 0.59 0.64)
			(layers "F.Cu" "F.Mask" "F.Paste")
			(roundrect_rratio 0.25)
			(net 3 "GNDREF")
			(pintype "passive")
		)
	)
	(footprint "antmicro-footprints:R_0402_1005Metric"
		(layer "F.Cu")
		(at 178.75 126.25 90)
		(descr "Resistor SMD 0402")
		(tags "resistor SMD 0402")
		(property "Reference" "R7"
			(at 11.75 1.45 270)
			(layer "B.SilkS")
			(effects
				(font
					(size 0.7 0.7)
					(thickness 0.15)
				)
				(justify left bottom mirror)
			)
		)
		(property "Value" "R_0R_0402"
			(at 0 1.4 90)
			(layer "F.Fab")
			(effects
				(font
					(size 0.7 0.7)
					(thickness 0.15)
				)
				(justify left bottom)
			)
		)
		(property "Description" "SMD Chip Resistor, Jumper, 0 ohm, 100 mW, 0402 [1005 Metric], Thick Film, General Purpose"
			(at 0 0 90)
			(layer "F.Fab")
			(hide yes)
			(effects
				(font
					(size 1.27 1.27)
					(thickness 0.15)
				)
			)
		)
		(property "Author" "Antmicro"
			(at 305 -52.5 0)
			(layer "F.Fab")
			(hide yes)
			(effects
				(font
					(size 1 1)
					(thickness 0.15)
				)
			)
		)
		(property "Current" "1A"
			(at 305 -52.5 0)
			(layer "F.Fab")
			(hide yes)
			(effects
				(font
					(size 1 1)
					(thickness 0.15)
				)
			)
		)
		(property "License" "Apache-2.0"
			(at 305 -52.5 0)
			(layer "F.Fab")
			(hide yes)
			(effects
				(font
					(size 1 1)
					(thickness 0.15)
				)
			)
		)
		(property "MPN" "ERJ2GE0R00X"
			(at 305 -52.5 0)
			(layer "F.Fab")
			(hide yes)
			(effects
				(font
					(size 1 1)
					(thickness 0.15)
				)
			)
		)
		(property "Manufacturer" "Panasonic"
			(at 305 -52.5 0)
			(layer "F.Fab")
			(hide yes)
			(effects
				(font
					(size 1 1)
					(thickness 0.15)
				)
			)
		)
		(property "Public" "False"
			(at 305 -52.5 0)
			(layer "F.Fab")
			(hide yes)
			(effects
				(font
					(size 1 1)
					(thickness 0.15)
				)
			)
		)
		(property "Tolerance" ""
			(at 305 -52.5 0)
			(layer "F.Fab")
			(hide yes)
			(effects
				(font
					(size 1 1)
					(thickness 0.15)
				)
			)
		)
		(property "Val" "0R"
			(at 305 -52.5 0)
			(layer "F.Fab")
			(hide yes)
			(effects
				(font
					(size 1 1)
					(thickness 0.15)
				)
			)
		)
		(sheetfile "environment-sensor.kicad_sch")
		(attr smd)
		(fp_rect
			(start -0.925 -0.47)
			(end 0.925 0.47)
			(stroke
				(width 0.05)
				(type default)
			)
			(fill no)
			(layer "F.CrtYd")
		)
		(fp_rect
			(start -0.5 -0.25)
			(end 0.5 0.25)
			(stroke
				(width 0.15)
				(type solid)
			)
			(fill no)
			(layer "F.Fab")
		)
		(pad "1" smd roundrect
			(at -0.48 0 90)
			(size 0.59 0.64)
			(layers "F.Cu" "F.Mask" "F.Paste")
			(roundrect_rratio 0.25)
			(net 39 "Net-(U1-DSR#)")
			(pintype "passive")
		)
		(pad "2" smd roundrect
			(at 0.48 0 90)
			(size 0.59 0.64)
			(layers "F.Cu" "F.Mask" "F.Paste")
			(roundrect_rratio 0.25)
			(net 13 "JTRST")
			(pintype "passive")
		)
	)
	(footprint "antmicro-footprints:MP_Pad5.4mm_Drill2.7mm"
		(layer "F.Cu")
		(at 206.4 136.4)
		(descr "Mounting Hole 2.7mm, M2.5")
		(tags "mounting hole 2.7mm m2.5")
		(property "Reference" "MP3"
			(at 1.2 3.4 0)
			(layer "F.SilkS")
			(effects
				(font
					(size 0.7 0.7)
					(thickness 0.15)
				)
				(justify left bottom)
			)
		)
		(property "Value" "MP_Pad5.4mm_Drill2.7mm"
			(at 0 3.6 0)
			(layer "F.Fab")
			(effects
				(font
					(size 0.7 0.7)
					(thickness 0.15)
				)
				(justify left bottom)
			)
		)
		(property "Description" "Mechanical part"
			(at 0 0 0)
			(layer "F.Fab")
			(hide yes)
			(effects
				(font
					(size 1.27 1.27)
					(thickness 0.15)
				)
			)
		)
		(property "Author" "Antmicro"
			(at 0 0 0)
			(layer "F.Fab")
			(hide yes)
			(effects
				(font
					(size 1 1)
					(thickness 0.15)
				)
			)
		)
		(property "License" "Apache-2.0"
			(at 0 0 0)
			(layer "F.Fab")
			(hide yes)
			(effects
				(font
					(size 1 1)
					(thickness 0.15)
				)
			)
		)
		(property "Public" "False"
			(at 0 0 0)
			(layer "F.Fab")
			(hide yes)
			(effects
				(font
					(size 1 1)
					(thickness 0.15)
				)
			)
		)
		(sheetfile "environment-sensor.kicad_sch")
		(attr exclude_from_pos_files exclude_from_bom)
		(pad "1" thru_hole circle
			(at 0 0)
			(size 5.4 5.4)
			(drill 2.7)
			(layers "*.Cu" "*.Mask")
			(remove_unused_layers no)
			(net 24 "unconnected-(MP3-Pad1)")
			(pintype "passive+no_connect")
		)
	)
	(footprint "antmicro-footprints:R_0402_1005Metric"
		(layer "F.Cu")
		(at 191.544 125.087 90)
		(descr "Resistor SMD 0402")
		(tags "resistor SMD 0402")
		(property "Reference" "R30"
			(at 2.887 3.556 0)
			(layer "F.SilkS")
			(effects
				(font
					(size 0.7 0.7)
					(thickness 0.15)
				)
				(justify left bottom)
			)
		)
		(property "Value" "R_100k_0402"
			(at 0 1.4 90)
			(layer "F.Fab")
			(effects
				(font
					(size 0.7 0.7)
					(thickness 0.15)
				)
				(justify left bottom)
			)
		)
		(property "Description" "SMD Chip Resistor, 100 kohm, ± 1%, 62.5 mW, 0402 [1005 Metric], Thick Film, General Purpose"
			(at 0 0 90)
			(layer "F.Fab")
			(hide yes)
			(effects
				(font
					(size 1.27 1.27)
					(thickness 0.15)
				)
			)
		)
		(property "Author" "Antmicro"
			(at 316.631 -66.457 0)
			(layer "F.Fab")
			(hide yes)
			(effects
				(font
					(size 1 1)
					(thickness 0.15)
				)
			)
		)
		(property "License" "Apache-2.0"
			(at 316.631 -66.457 0)
			(layer "F.Fab")
			(hide yes)
			(effects
				(font
					(size 1 1)
					(thickness 0.15)
				)
			)
		)
		(property "MPN" "CR0402-FX-1003GLF"
			(at 316.631 -66.457 0)
			(layer "F.Fab")
			(hide yes)
			(effects
				(font
					(size 1 1)
					(thickness 0.15)
				)
			)
		)
		(property "Manufacturer" "Bourns"
			(at 316.631 -66.457 0)
			(layer "F.Fab")
			(hide yes)
			(effects
				(font
					(size 1 1)
					(thickness 0.15)
				)
			)
		)
		(property "Public" "False"
			(at 316.631 -66.457 0)
			(layer "F.Fab")
			(hide yes)
			(effects
				(font
					(size 1 1)
					(thickness 0.15)
				)
			)
		)
		(property "Tolerance" "1%"
			(at 316.631 -66.457 0)
			(layer "F.Fab")
			(hide yes)
			(effects
				(font
					(size 1 1)
					(thickness 0.15)
				)
			)
		)
		(property "Val" "100k"
			(at 316.631 -66.457 0)
			(layer "F.Fab")
			(hide yes)
			(effects
				(font
					(size 1 1)
					(thickness 0.15)
				)
			)
		)
		(sheetfile "environment-sensor.kicad_sch")
		(attr smd exclude_from_pos_files exclude_from_bom dnp)
		(fp_rect
			(start -0.925 -0.47)
			(end 0.925 0.47)
			(stroke
				(width 0.05)
				(type default)
			)
			(fill no)
			(layer "F.CrtYd")
		)
		(fp_rect
			(start -0.5 -0.25)
			(end 0.5 0.25)
			(stroke
				(width 0.15)
				(type solid)
			)
			(fill no)
			(layer "F.Fab")
		)
		(pad "1" smd roundrect
			(at -0.48 0 90)
			(size 0.59 0.64)
			(layers "F.Cu" "F.Mask" "F.Paste")
			(roundrect_rratio 0.25)
			(net 1 "GND")
			(pintype "passive")
		)
		(pad "2" smd roundrect
			(at 0.48 0 90)
			(size 0.59 0.64)
			(layers "F.Cu" "F.Mask" "F.Paste")
			(roundrect_rratio 0.25)
			(net 49 "Net-(U3-PB8-BOOT0)")
			(pintype "passive")
		)
	)
	(footprint "antmicro-footprints:TP_SMD_1mm"
		(layer "F.Cu")
		(at 197.411 127.476 180)
		(property "Reference" "TP8"
			(at 0 -0.731898 180)
			(layer "F.SilkS")
			(hide yes)
			(effects
				(font
					(size 0.7 0.7)
					(thickness 0.15)
				)
				(justify left bottom)
			)
		)
		(property "Value" "TP_1mm_SMD"
			(at 0 1.4 180)
			(layer "F.Fab")
			(effects
				(font
					(size 0.7 0.7)
					(thickness 0.15)
				)
				(justify left bottom)
			)
		)
		(property "Description" "Test point 1mm SMD"
			(at 0 0 180)
			(layer "F.Fab")
			(hide yes)
			(effects
				(font
					(size 1.27 1.27)
					(thickness 0.15)
				)
			)
		)
		(property "Author" "Antmicro"
			(at 394.822 254.952 0)
			(layer "F.Fab")
			(hide yes)
			(effects
				(font
					(size 1 1)
					(thickness 0.15)
				)
			)
		)
		(property "License" "Apache-2.0"
			(at 394.822 254.952 0)
			(layer "F.Fab")
			(hide yes)
			(effects
				(font
					(size 1 1)
					(thickness 0.15)
				)
			)
		)
		(property "MPN" ""
			(at 394.822 254.952 0)
			(layer "F.Fab")
			(hide yes)
			(effects
				(font
					(size 1 1)
					(thickness 0.15)
				)
			)
		)
		(property "Manufacturer" ""
			(at 394.822 254.952 0)
			(layer "F.Fab")
			(hide yes)
			(effects
				(font
					(size 1 1)
					(thickness 0.15)
				)
			)
		)
		(property "Public" "False"
			(at 394.822 254.952 0)
			(layer "F.Fab")
			(hide yes)
			(effects
				(font
					(size 1 1)
					(thickness 0.15)
				)
			)
		)
		(sheetfile "environment-sensor.kicad_sch")
		(attr exclude_from_pos_files)
		(pad "1" smd circle
			(at 0 0 180)
			(size 1 1)
			(layers "F.Cu" "F.Mask")
			(net 49 "Net-(U3-PB8-BOOT0)")
			(pinfunction "1")
			(pintype "passive")
		)
	)
	(footprint "antmicro-footprints:C_0402_1005Metric"
		(layer "F.Cu")
		(at 191.314 138.424 90)
		(descr "Capacitor SMD 0402")
		(tags "capacitor SMD 0402")
		(property "Reference" "C22"
			(at 17.955 -8.3245 90)
			(layer "B.SilkS")
			(effects
				(font
					(size 0.7 0.7)
					(thickness 0.15)
				)
				(justify left bottom mirror)
			)
		)
		(property "Value" "C_100n_0402"
			(at 0 1.4 90)
			(layer "F.Fab")
			(effects
				(font
					(size 0.7 0.7)
					(thickness 0.15)
				)
				(justify left bottom)
			)
		)
		(property "Description" "SMD Multilayer Ceramic Capacitor, 0.1 µF, 50 V, 0402 [1005 Metric], ± 10%, X5R, GRM Series"
			(at 0 0 90)
			(layer "F.Fab")
			(hide yes)
			(effects
				(font
					(size 1.27 1.27)
					(thickness 0.15)
				)
			)
		)
		(property "Author" "Antmicro"
			(at 329.738 -52.89 0)
			(layer "F.Fab")
			(hide yes)
			(effects
				(font
					(size 1 1)
					(thickness 0.15)
				)
			)
		)
		(property "Dielectric" "X5R"
			(at 329.738 -52.89 0)
			(layer "F.Fab")
			(hide yes)
			(effects
				(font
					(size 1 1)
					(thickness 0.15)
				)
			)
		)
		(property "License" "Apache-2.0"
			(at 329.738 -52.89 0)
			(layer "F.Fab")
			(hide yes)
			(effects
				(font
					(size 1 1)
					(thickness 0.15)
				)
			)
		)
		(property "MPN" "GRM155R61H104KE14D"
			(at 329.738 -52.89 0)
			(layer "F.Fab")
			(hide yes)
			(effects
				(font
					(size 1 1)
					(thickness 0.15)
				)
			)
		)
		(property "Manufacturer" "Murata"
			(at 329.738 -52.89 0)
			(layer "F.Fab")
			(hide yes)
			(effects
				(font
					(size 1 1)
					(thickness 0.15)
				)
			)
		)
		(property "Public" "False"
			(at 329.738 -52.89 0)
			(layer "F.Fab")
			(hide yes)
			(effects
				(font
					(size 1 1)
					(thickness 0.15)
				)
			)
		)
		(property "Val" "100n"
			(at 329.738 -52.89 0)
			(layer "F.Fab")
			(hide yes)
			(effects
				(font
					(size 1 1)
					(thickness 0.15)
				)
			)
		)
		(property "Voltage" "50V"
			(at 329.738 -52.89 0)
			(layer "F.Fab")
			(hide yes)
			(effects
				(font
					(size 1 1)
					(thickness 0.15)
				)
			)
		)
		(sheetfile "environment-sensor.kicad_sch")
		(attr smd)
		(fp_rect
			(start -0.925 -0.47)
			(end 0.925 0.47)
			(stroke
				(width 0.05)
				(type default)
			)
			(fill no)
			(layer "F.CrtYd")
		)
		(fp_line
			(start 0.504 -0.25)
			(end 0.504 0.248)
			(stroke
				(width 0.15)
				(type solid)
			)
			(layer "F.Fab")
		)
		(fp_line
			(start -0.494 -0.25)
			(end 0.504 -0.25)
			(stroke
				(width 0.15)
				(type solid)
			)
			(layer "F.Fab")
		)
		(fp_line
			(start 0.504 0.248)
			(end -0.494 0.248)
			(stroke
				(width 0.15)
				(type solid)
			)
			(layer "F.Fab")
		)
		(fp_line
			(start -0.494 0.248)
			(end -0.494 -0.25)
			(stroke
				(width 0.15)
				(type solid)
			)
			(layer "F.Fab")
		)
		(pad "1" smd roundrect
			(at -0.48 0 90)
			(size 0.59 0.64)
			(layers "F.Cu" "F.Mask" "F.Paste")
			(roundrect_rratio 0.25)
			(net 32 "Net-(U3-VREF+)")
			(pintype "passive")
		)
		(pad "2" smd roundrect
			(at 0.48 0 90)
			(size 0.59 0.64)
			(layers "F.Cu" "F.Mask" "F.Paste")
			(roundrect_rratio 0.25)
			(net 1 "GND")
			(pintype "passive")
		)
	)
	(footprint "antmicro-footprints:R_0402_1005Metric"
		(layer "F.Cu")
		(at 192.644 125.087 90)
		(descr "Resistor SMD 0402")
		(tags "resistor SMD 0402")
		(property "Reference" "R29"
			(at 1.887 2.456 0)
			(layer "F.SilkS")
			(effects
				(font
					(size 0.7 0.7)
					(thickness 0.15)
				)
				(justify left bottom)
			)
		)
		(property "Value" "R_100k_0402"
			(at 0 1.4 90)
			(layer "F.Fab")
			(effects
				(font
					(size 0.7 0.7)
					(thickness 0.15)
				)
				(justify left bottom)
			)
		)
		(property "Description" "SMD Chip Resistor, 100 kohm, ± 1%, 62.5 mW, 0402 [1005 Metric], Thick Film, General Purpose"
			(at 0 0 90)
			(layer "F.Fab")
			(hide yes)
			(effects
				(font
					(size 1.27 1.27)
					(thickness 0.15)
				)
			)
		)
		(property "Author" "Antmicro"
			(at 317.731 -67.557 0)
			(layer "F.Fab")
			(hide yes)
			(effects
				(font
					(size 1 1)
					(thickness 0.15)
				)
			)
		)
		(property "License" "Apache-2.0"
			(at 317.731 -67.557 0)
			(layer "F.Fab")
			(hide yes)
			(effects
				(font
					(size 1 1)
					(thickness 0.15)
				)
			)
		)
		(property "MPN" "CR0402-FX-1003GLF"
			(at 317.731 -67.557 0)
			(layer "F.Fab")
			(hide yes)
			(effects
				(font
					(size 1 1)
					(thickness 0.15)
				)
			)
		)
		(property "Manufacturer" "Bourns"
			(at 317.731 -67.557 0)
			(layer "F.Fab")
			(hide yes)
			(effects
				(font
					(size 1 1)
					(thickness 0.15)
				)
			)
		)
		(property "Public" "False"
			(at 317.731 -67.557 0)
			(layer "F.Fab")
			(hide yes)
			(effects
				(font
					(size 1 1)
					(thickness 0.15)
				)
			)
		)
		(property "Tolerance" "1%"
			(at 317.731 -67.557 0)
			(layer "F.Fab")
			(hide yes)
			(effects
				(font
					(size 1 1)
					(thickness 0.15)
				)
			)
		)
		(property "Val" "100k"
			(at 317.731 -67.557 0)
			(layer "F.Fab")
			(hide yes)
			(effects
				(font
					(size 1 1)
					(thickness 0.15)
				)
			)
		)
		(sheetfile "environment-sensor.kicad_sch")
		(attr smd)
		(fp_rect
			(start -0.925 -0.47)
			(end 0.925 0.47)
			(stroke
				(width 0.05)
				(type default)
			)
			(fill no)
			(layer "F.CrtYd")
		)
		(fp_rect
			(start -0.5 -0.25)
			(end 0.5 0.25)
			(stroke
				(width 0.15)
				(type solid)
			)
			(fill no)
			(layer "F.Fab")
		)
		(pad "1" smd roundrect
			(at -0.48 0 90)
			(size 0.59 0.64)
			(layers "F.Cu" "F.Mask" "F.Paste")
			(roundrect_rratio 0.25)
			(net 49 "Net-(U3-PB8-BOOT0)")
			(pintype "passive")
		)
		(pad "2" smd roundrect
			(at 0.48 0 90)
			(size 0.59 0.64)
			(layers "F.Cu" "F.Mask" "F.Paste")
			(roundrect_rratio 0.25)
			(net 2 "+3V3")
			(pintype "passive")
		)
	)
)
